# T6G (Grand Teton) — schematic netlist excerpt (pin names and nets, part order shuffled) for the footprints in the layout excerpt that follows; sources: Cadence DE-HDL packaged netlist, KiCad conversion of 04192023_DAF0TMB3IC0_F0TG_MB_C_brd_V02_OCP.brd

R522  Q_RES  2.2K 5% CHIP  pkg 0402LF  page 54 : A = P3V3_AUX ; B = CPU1_SP5R1
C563  Q_CAP  22UF 4V 20% X6S  pkg C0402  page 279 : A = P0V9_CPU0_RT_2D ; B = GND
C6740  Q_CAP_DIFFBUS  DIFF BUS_0.22UF 6.3V 20% X6S  pkg C0201  page 352 : \1\ = P5E_CPU1_P3_TX_BUF_C_DN<7> ; \2\ = P5E_CPU1_P3_TX_BUF_DN<7>

(kicad_pcb
	(version 20260206)
	(generator "pcbnew")
	(generator_version "10.0")
	(general
		(thickness 1.6)
		(legacy_teardrops no)
	)
	(paper "A4")
	(title_block
		(title "04192023_DAF0TMB3IC0_F0TG_MB_C_brd_V02_OCP.brd")
		(comment 1 "Grand Teton / footprints 7253-7255 of 8354")
	)
	(layers
		(0 "F.Cu" signal "TOP")
		(4 "In1.Cu" signal "GND")
		(6 "In2.Cu" signal "IN1")
		(8 "In3.Cu" signal "GND1")
		(10 "In4.Cu" signal "IN2")
		(12 "In5.Cu" signal "GND2")
		(14 "In6.Cu" signal "IN3")
		(16 "In7.Cu" signal "GND3")
		(18 "In8.Cu" signal "VCC")
		(20 "In9.Cu" signal "VCC1")
		(22 "In10.Cu" signal "GND4")
		(24 "In11.Cu" signal "IN4")
		(26 "In12.Cu" signal "GND5")
		(28 "In13.Cu" signal "IN5")
		(30 "In14.Cu" signal "GND6")
		(32 "In15.Cu" signal "IN6")
		(34 "In16.Cu" signal "GND7")
		(2 "B.Cu" signal "BOTTOM")
		(9 "F.Adhes" user "F.Adhesive")
		(11 "B.Adhes" user "B.Adhesive")
		(13 "F.Paste" user "Package Geometry/Pastemask Top")
		(15 "B.Paste" user "Package Geometry/Pastemask Bottom")
		(5 "F.SilkS" user "Ref Des/Silkscreen Top")
		(7 "B.SilkS" user "Ref Des/Silkscreen Bottom")
		(1 "F.Mask" user "Board Geometry/Soldermask Top")
		(3 "B.Mask" user "Board Geometry/Soldermask Bottom")
		(17 "Dwgs.User" user "User.Drawings")
		(19 "Cmts.User" user "User.Comments")
		(21 "Eco1.User" user "User.Eco1")
		(23 "Eco2.User" user "User.Eco2")
		(25 "Edge.Cuts" user "Board Geometry/Outline")
		(27 "Margin" user)
		(31 "F.CrtYd" user "Package Geometry/Place Bound Top")
		(29 "B.CrtYd" user "Package Geometry/Place Bound Bottom")
		(35 "F.Fab" user "Ref Des/Assembly Top")
		(33 "B.Fab" user "Ref Des/Assembly Bottom")
	)
	(footprint ""
		(layer "B.Cu")
		(at 145.331434 -203.679552 90)
		(property "Reference" "R522"
			(at 0 0 90)
			(layer "B.SilkS")
			(hide yes)
			(effects
				(font
					(size 1.27 1.27)
				)
				(justify mirror)
			)
		)
		(property "Value" ""
			(at 0 0 90)
			(layer "B.Fab")
			(effects
				(font
					(size 1.27 1.27)
				)
				(justify mirror)
			)
		)
		(duplicate_pad_numbers_are_jumpers no)
		(fp_line
			(start 0.7874 -0.4064)
			(end -0.7874 -0.4064)
			(stroke
				(width 0.1524)
				(type default)
			)
			(layer "B.SilkS")
		)
		(fp_line
			(start -0.7874 -0.4064)
			(end -0.7874 0.4064)
			(stroke
				(width 0.1524)
				(type default)
			)
			(layer "B.SilkS")
		)
		(fp_line
			(start 0.7874 0.4064)
			(end 0.7874 -0.4064)
			(stroke
				(width 0.1524)
				(type default)
			)
			(layer "B.SilkS")
		)
		(fp_line
			(start -0.7874 0.4064)
			(end 0.7874 0.4064)
			(stroke
				(width 0.1524)
				(type default)
			)
			(layer "B.SilkS")
		)
		(fp_line
			(start 0.67945 -0.305054)
			(end 0.12065 -0.305054)
			(stroke
				(width 0.1)
				(type default)
			)
			(layer "B.Fab")
		)
		(fp_line
			(start 0.12065 -0.305054)
			(end 0.12065 -0.2794)
			(stroke
				(width 0.1)
				(type default)
			)
			(layer "B.Fab")
		)
		(fp_line
			(start -0.12065 -0.3048)
			(end -0.67945 -0.3048)
			(stroke
				(width 0.1)
				(type default)
			)
			(layer "B.Fab")
		)
		(fp_line
			(start -0.67945 -0.3048)
			(end -0.67945 0.3048)
			(stroke
				(width 0.1)
				(type default)
			)
			(layer "B.Fab")
		)
		(fp_line
			(start 0.12065 -0.2794)
			(end -0.12065 -0.2794)
			(stroke
				(width 0.1)
				(type default)
			)
			(layer "B.Fab")
		)
		(fp_line
			(start -0.12065 -0.2794)
			(end -0.12065 -0.3048)
			(stroke
				(width 0.1)
				(type default)
			)
			(layer "B.Fab")
		)
		(fp_line
			(start 0.12065 0.2794)
			(end 0.12065 0.3048)
			(stroke
				(width 0.1)
				(type default)
			)
			(layer "B.Fab")
		)
		(fp_line
			(start -0.120396 0.2794)
			(end 0.12065 0.2794)
			(stroke
				(width 0.1)
				(type default)
			)
			(layer "B.Fab")
		)
		(fp_line
			(start 0.67945 0.3048)
			(end 0.67945 -0.305054)
			(stroke
				(width 0.1)
				(type default)
			)
			(layer "B.Fab")
		)
		(fp_line
			(start 0.12065 0.3048)
			(end 0.67945 0.3048)
			(stroke
				(width 0.1)
				(type default)
			)
			(layer "B.Fab")
		)
		(fp_line
			(start -0.120396 0.3048)
			(end -0.120396 0.2794)
			(stroke
				(width 0.1)
				(type default)
			)
			(layer "B.Fab")
		)
		(fp_line
			(start -0.67945 0.3048)
			(end -0.120396 0.3048)
			(stroke
				(width 0.1)
				(type default)
			)
			(layer "B.Fab")
		)
		(pad "1" smd circle
			(at 0.40005 0 270)
			(size 0 0)
			(layers "B.Cu" "B.Mask" "B.Paste")
			(net "P3V3_AUX")
		)
		(pad "2" smd circle
			(at -0.40005 0 270)
			(size 0 0)
			(layers "B.Cu" "B.Mask" "B.Paste")
			(net "CPU1_SP5R1")
		)
	)
	(footprint ""
		(layer "B.Cu")
		(at 137.843006 -408.517344 90)
		(property "Reference" "C6740"
			(at 0 0 90)
			(layer "B.SilkS")
			(hide yes)
			(effects
				(font
					(size 1.27 1.27)
				)
				(justify mirror)
			)
		)
		(property "Value" ""
			(at 0 0 90)
			(layer "B.Fab")
			(effects
				(font
					(size 1.27 1.27)
				)
				(justify mirror)
			)
		)
		(duplicate_pad_numbers_are_jumpers no)
		(fp_line
			(start 0.299974 -0.150114)
			(end -0.299974 -0.150114)
			(stroke
				(width 0.1)
				(type default)
			)
			(layer "B.Fab")
		)
		(fp_line
			(start -0.299974 -0.150114)
			(end -0.299974 0.150114)
			(stroke
				(width 0.1)
				(type default)
			)
			(layer "B.Fab")
		)
		(fp_line
			(start 0.299974 0.150114)
			(end 0.299974 -0.150114)
			(stroke
				(width 0.1)
				(type default)
			)
			(layer "B.Fab")
		)
		(fp_line
			(start -0.299974 0.150114)
			(end 0.299974 0.150114)
			(stroke
				(width 0.1)
				(type default)
			)
			(layer "B.Fab")
		)
		(pad "1" smd rect
			(at 0.2667 0 270)
			(size 0.3048 0.381)
			(layers "B.Cu" "B.Mask" "B.Paste")
			(net "P5E_CPU1_P3_TX_BUF_C_DN<7>")
		)
		(pad "2" smd rect
			(at -0.2667 0 270)
			(size 0.3048 0.381)
			(layers "B.Cu" "B.Mask" "B.Paste")
			(net "P5E_CPU1_P3_TX_BUF_DN<7>")
		)
	)
	(footprint ""
		(layer "B.Cu")
		(at 314.191142 -398.942052 90)
		(property "Reference" "C563"
			(at 0 0 90)
			(layer "B.SilkS")
			(hide yes)
			(effects
				(font
					(size 1.27 1.27)
				)
				(justify mirror)
			)
		)
		(property "Value" ""
			(at 0 0 90)
			(layer "B.Fab")
			(effects
				(font
					(size 1.27 1.27)
				)
				(justify mirror)
			)
		)
		(duplicate_pad_numbers_are_jumpers no)
		(fp_line
			(start 0.7874 -0.4064)
			(end -0.7874 -0.4064)
			(stroke
				(width 0.1524)
				(type default)
			)
			(layer "B.SilkS")
		)
		(fp_line
			(start -0.7874 -0.4064)
			(end -0.7874 0.4064)
			(stroke
				(width 0.1524)
				(type default)
			)
			(layer "B.SilkS")
		)
		(fp_line
			(start 0.7874 0.4064)
			(end 0.7874 -0.4064)
			(stroke
				(width 0.1524)
				(type default)
			)
			(layer "B.SilkS")
		)
		(fp_line
			(start -0.7874 0.4064)
			(end 0.7874 0.4064)
			(stroke
				(width 0.1524)
				(type default)
			)
			(layer "B.SilkS")
		)
		(fp_line
			(start 0.67945 -0.305054)
			(end 0.12065 -0.305054)
			(stroke
				(width 0.1)
				(type default)
			)
			(layer "B.Fab")
		)
		(fp_line
			(start 0.12065 -0.305054)
			(end 0.12065 -0.2794)
			(stroke
				(width 0.1)
				(type default)
			)
			(layer "B.Fab")
		)
		(fp_line
			(start -0.12065 -0.3048)
			(end -0.67945 -0.3048)
			(stroke
				(width 0.1)
				(type default)
			)
			(layer "B.Fab")
		)
		(fp_line
			(start -0.67945 -0.3048)
			(end -0.67945 0.3048)
			(stroke
				(width 0.1)
				(type default)
			)
			(layer "B.Fab")
		)
		(fp_line
			(start 0.12065 -0.2794)
			(end -0.12065 -0.2794)
			(stroke
				(width 0.1)
				(type default)
			)
			(layer "B.Fab")
		)
		(fp_line
			(start -0.12065 -0.2794)
			(end -0.12065 -0.3048)
			(stroke
				(width 0.1)
				(type default)
			)
			(layer "B.Fab")
		)
		(fp_line
			(start 0.12065 0.2794)
			(end 0.12065 0.3048)
			(stroke
				(width 0.1)
				(type default)
			)
			(layer "B.Fab")
		)
		(fp_line
			(start -0.120396 0.2794)
			(end 0.12065 0.2794)
			(stroke
				(width 0.1)
				(type default)
			)
			(layer "B.Fab")
		)
		(fp_line
			(start 0.67945 0.3048)
			(end 0.67945 -0.305054)
			(stroke
				(width 0.1)
				(type default)
			)
			(layer "B.Fab")
		)
		(fp_line
			(start 0.12065 0.3048)
			(end 0.67945 0.3048)
			(stroke
				(width 0.1)
				(type default)
			)
			(layer "B.Fab")
		)
		(fp_line
			(start -0.120396 0.3048)
			(end -0.120396 0.2794)
			(stroke
				(width 0.1)
				(type default)
			)
			(layer "B.Fab")
		)
		(fp_line
			(start -0.67945 0.3048)
			(end -0.120396 0.3048)
			(stroke
				(width 0.1)
				(type default)
			)
			(layer "B.Fab")
		)
		(pad "1" smd circle
			(at 0.40005 0 270)
			(size 0 0)
			(layers "B.Cu" "B.Mask" "B.Paste")
			(net "P0V9_CPU0_RT_2D")
		)
		(pad "2" smd circle
			(at -0.40005 0 270)
			(size 0 0)
			(layers "B.Cu" "B.Mask" "B.Paste")
			(net "GND")
		)
	)
)
